FILE_TYPE = CONNECTIVITY;
{Allegro Design Entry HDL 16.6-p007 (v16-6-112F) 10/10/2012}
"PAGE_NUMBER" = 195;
0"NC";
1"P12V_STBY\g";
2"GND\g";
3"GND\g";
4"P12V_PSU\g";
5"GND\g";
6"GND\g";
7"GND\g";
8"GND\g";
9"P12V_PSU\g";
10"P12V_PSU\g";
11"GND\g";
12"GND\g";
13"GND\g";
14"GND\g";
15"GND\g";
16"GND\g";
17"GND\g";
18"P12V_PSU\g";
19"GND\g";
20"P12V_PSU\g";
21"GND\g";
22"P12V_STBY\g";
23"P12V_STBY\g";
24"GND\g";
25"GND\g";
%"CAPP"
"1","(-7700,775)","0","mstr_discrete","I100";
;
CDS_SEC"1"
PACK_TYPE"3018"
MATERIAL"TANT"
PART_NUMBER"724613-112"
VOLTAGE"16V"
TOLERANCE"20%"
VALUE"68UF"
LOCATION"C3B6"
SEC_TYPE"3018"
SEC"1"
CDS_LIB"mstr_discrete"
CDS_LOCATION"C3B6";
"B"
$PN"2"24;
"A"
$PN"1"23;
%"CAPP"
"1","(-6175,775)","0","mstr_discrete","I101";
;
CDS_SEC"1"
PART_NUMBER"724613-112"
PACK_TYPE"3018"
MATERIAL"TANT"
VOLTAGE"16V"
TOLERANCE"20%"
VALUE"68UF"
LOCATION"C1R23"
SEC_TYPE"3018"
SEC"1"
CDS_LIB"mstr_discrete"
CDS_LOCATION"C1R23";
"B"
$PN"2"24;
"A"
$PN"1"23;
%"CAPP"
"1","(-4875,775)","0","mstr_discrete","I102";
;
CDS_SEC"1"
VOLTAGE"16V"
PACK_TYPE"3018"
MATERIAL"TANT"
TOLERANCE"20%"
VALUE"68UF"
LOCATION"C4M6"
PART_NUMBER"724613-112"
SEC_TYPE"3018"
SEC"1"
CDS_LIB"mstr_discrete"
CDS_LOCATION"C4M6";
"B"
$PN"2"24;
"A"
$PN"1"23;
%"CAPP"
"1","(-6550,775)","0","mstr_discrete","I103";
;
CDS_SEC"1"
PACK_TYPE"3018"
MATERIAL"TANT"
PART_NUMBER"724613-112"
VOLTAGE"16V"
TOLERANCE"20%"
VALUE"68UF"
LOCATION"C1M5"
SEC_TYPE"3018"
SEC"1"
CDS_LIB"mstr_discrete"
CDS_LOCATION"C1M5";
"B"
$PN"2"24;
"A"
$PN"1"23;
%"CAPP"
"1","(-5725,1950)","0","mstr_discrete","I104";
;
CDS_SEC"1"
VALUE"68UF"
LOCATION"C3T13"
PACK_TYPE"3018"
PART_NUMBER"724613-112"
MATERIAL"TANT"
VOLTAGE"16V"
TOLERANCE"20%"
SEC_TYPE"3018"
SEC"1"
CDS_LIB"mstr_discrete"
CDS_LOCATION"C3T13";
"B"
$PN"2"2;
"A"
$PN"1"1;
%"CAPP"
"1","(-4850,1950)","0","mstr_discrete","I105";
;
CDS_SEC"1"
PACK_TYPE"3018"
VOLTAGE"16V"
MATERIAL"TANT"
PART_NUMBER"724613-112"
VALUE"68UF"
TOLERANCE"20%"
LOCATION"C4M7"
SEC_TYPE"3018"
SEC"1"
CDS_LIB"mstr_discrete"
CDS_LOCATION"C4M7";
"B"
$PN"2"2;
"A"
$PN"1"1;
%"CAPP"
"1","(-5275,1925)","0","mstr_discrete","I106";
;
CDS_SEC"1"
PACK_TYPE"3018"
LOCATION"C3T15"
PART_NUMBER"724613-112"
VALUE"68UF"
MATERIAL"TANT"
TOLERANCE"20%"
VOLTAGE"16V"
SEC_TYPE"3018"
SEC"1"
CDS_LOCATION"C3T15"
CDS_LIB"mstr_discrete";
"B"
$PN"2"2;
"A"
$PN"1"1;
%"P12V_STBY"
"1","(-6375,2325)","0","mstr_symbols","I107";
;
VOLTAGE"12.0V"
SIZE"1B"
CDS_LIB"mstr_symbols"
BODY_TYPE"PLUMBING"
HDL_POWER"P12V_STBY";
"G\NAC"1;
%"CAPP"
"1","(-6150,1950)","0","mstr_discrete","I108";
;
CDS_SEC"1"
MATERIAL"TANT"
VOLTAGE"16V"
PACK_TYPE"3018"
TOLERANCE"20%"
PART_NUMBER"724613-112"
VALUE"68UF"
LOCATION"C7M6"
SEC_TYPE"3018"
SEC"1"
CDS_LIB"mstr_discrete"
CDS_LOCATION"C7M6";
"B"
$PN"2"2;
"A"
$PN"1"1;
%"CAPP"
"1","(-6525,1950)","0","mstr_discrete","I109";
;
CDS_SEC"1"
PART_NUMBER"724613-112"
PACK_TYPE"3018"
VOLTAGE"16V"
MATERIAL"TANT"
TOLERANCE"20%"
VALUE"68UF"
LOCATION"C6N5"
SEC_TYPE"3018"
SEC"1"
CDS_LIB"mstr_discrete"
CDS_LOCATION"C6N5";
"B"
$PN"2"2;
"A"
$PN"1"1;
%"GND"
"1","(-6375,1500)","0","mstr_symbols","I110";
;
VOLTAGE"0.0V"
SIZE"1B"
CDS_LIB"mstr_symbols"
BODY_TYPE"PLUMBING"
HDL_POWER"GND";
"A\NAC"2;
%"CAPP"
"1","(-6875,1950)","0","mstr_discrete","I111";
;
CDS_SEC"1"
PART_NUMBER"724613-112"
PACK_TYPE"3018"
MATERIAL"TANT"
VOLTAGE"16V"
TOLERANCE"20%"
VALUE"68UF"
LOCATION"C9T3"
SEC_TYPE"3018"
SEC"1"
CDS_LIB"mstr_discrete"
CDS_LOCATION"C9T3";
"B"
$PN"2"2;
"A"
$PN"1"1;
%"CAPP"
"1","(-7250,1950)","0","mstr_discrete","I112";
;
CDS_SEC"1"
PACK_TYPE"3018"
TOLERANCE"20%"
VOLTAGE"16V"
MATERIAL"TANT"
PART_NUMBER"724613-112"
VALUE"68UF"
LOCATION"C4F4"
SEC_TYPE"3018"
SEC"1"
CDS_LIB"mstr_discrete"
CDS_LOCATION"C4F4";
"B"
$PN"2"2;
"A"
$PN"1"1;
%"CAPP"
"1","(-7675,1950)","0","mstr_discrete","I113";
;
CDS_SEC"1"
PACK_TYPE"3018"
VALUE"68UF"
TOLERANCE"20%"
VOLTAGE"16V"
MATERIAL"TANT"
PART_NUMBER"724613-112"
LOCATION"C3T3"
SEC_TYPE"3018"
SEC"1"
CDS_LIB"mstr_discrete"
CDS_LOCATION"C3T3";
"B"
$PN"2"2;
"A"
$PN"1"1;
%"FCI-CONN12-2R-GP"
"1","(-3025,2150)","0","w_hdl","I114";
;
CDS_SEC"1"
CDS_LOCATION"J1E1"
VALUE"FCI-CONN12-2R-GP"
LOCATION"J1E1"
CDS_LMAN_SYM_OUTLINE"-175,300,175,-300"
CDS_LIB"w_hdl"
PART_NUMBER"20.82093.012"
SEC_TYPE"CONN-G5"
SEC"1"
PACK_TYPE"CONN-G5";
"4_3"
$PN"4_3"8;
"4_2"
$PN"4_2"8;
"4_1"
$PN"4_1"8;
"1_3"
$PN"1_3"9;
"1_2"
$PN"1_2"9;
"1_1"
$PN"1_1"9;
"NP1"
$PN"NP1"0;
"3_3"
$PN"3_3"6;
"3_2"
$PN"3_2"6;
"3_1"
$PN"3_1"6;
"2_3"
$PN"2_3"4;
"2_2"
$PN"2_2"4;
"2_1"
$PN"2_1"4;
%"FCI-CONN12-2R-GP"
"1","(-1250,2150)","0","w_hdl","I115";
;
CDS_SEC"1"
CDS_LOCATION"J1D1"
POP"NOPOP"
VALUE"FCI-CONN12-2R-GP"
LOCATION"J1D1"
PACK_TYPE"CONN-G5"
SEC"1"
SEC_TYPE"CONN-G5"
PART_NUMBER"20.82093.012"
CDS_LIB"w_hdl"
CDS_LMAN_SYM_OUTLINE"-175,300,175,-300";
"4_3"
$PN"4_3"19;
"4_2"
$PN"4_2"19;
"4_1"
$PN"4_1"19;
"1_3"
$PN"1_3"18;
"1_2"
$PN"1_2"18;
"1_1"
$PN"1_1"18;
"NP1"
$PN"NP1"0;
"3_3"
$PN"3_3"21;
"3_2"
$PN"3_2"21;
"3_1"
$PN"3_1"21;
"2_3"
$PN"2_3"20;
"2_2"
$PN"2_2"20;
"2_1"
$PN"2_1"20;
%"STFT363B238R224H453-GP"
"1","(-7650,4750)","0","w_hdl","I117";
;
CDS_SEC"1"
CDS_LOCATION"RM1G1"
LOCATION"RM1G1"
VALUE"STFT363B238R224H453-GP"
CDS_LMAN_SYM_OUTLINE"-100,100,100,-100"
CDS_LIB"w_hdl"
PART_NUMBER"086.2AT24.04R6"
PACK_TYPE"DISCRET-GC1"
SEC"1"
SEC_TYPE"DISCRET-GC1";
"1 \B"
$PN"1"3;
%"GND"
"1","(-7350,4650)","0","mstr_symbols","I118";
;
VOLTAGE"0.0V"
CDS_LIB"mstr_symbols"
SIZE"1B"
BODY_TYPE"PLUMBING"
HDL_POWER"GND";
"A\NAC"3;
%"P12V_PSU"
"1","(-3700,2750)","0","mstr_symbols","I25";
;
VOLTAGE"12.0"
BOM_COST"NT_BASE_VRD"
CDS_LIB"mstr_symbols"
ROOM"P2V5_LAN_AUX_VR"
BODY_TYPE"PLUMBING"
HDL_POWER"P12V_PSU";
"G\NAC"4;
%"CONN3_G98259001"
"1","(-925,3725)","0","mstr_conn","I26";
;
PART_NUMBER"G98259-001"
MATERIAL"CONN"
LOCATION"RM1E1"
CDS_LOCATION"RM1E1"
$SEC"1"
CDS_SEC"1"
PACK_TYPE"PIP"
CDS_LMAN_SYM_OUTLINE"-150,200,150,-200"
CDS_LIB"mstr_conn";
"IO3"
$PN"3"5;
"IO2"
$PN"2"5;
"IO1"
$PN"1"5;
%"GND"
"1","(-475,3375)","0","mstr_symbols","I27";
;
VOLTAGE"0.0V"
SIZE"1B"
CDS_LIB"mstr_symbols"
BODY_TYPE"PLUMBING"
HDL_POWER"GND";
"A\NAC"5;
%"GND"
"1","(-3550,1900)","0","mstr_symbols","I28";
;
VOLTAGE"0.0V"
SIZE"1B"
CDS_LIB"mstr_symbols"
BODY_TYPE"PLUMBING"
HDL_POWER"GND";
"A\NAC"6;
%"GND"
"1","(-3700,3225)","0","mstr_symbols","I30";
;
VOLTAGE"0.0V"
SIZE"1B"
CDS_LIB"mstr_symbols"
BODY_TYPE"PLUMBING"
HDL_POWER"GND";
"A\NAC"7;
%"CAP"
"1","(-3700,3650)","0","mstr_discrete","I31";
;
CDS_SEC"1"
VOLTAGE"16V"
PART_NUMBER"C95333-007"
POP"NOPOP"
TOLERANCE"10%"
VALUE"10UF"
PACK_TYPE"0805"
MATERIAL"X6S"
LOCATION"C9R5"
SEC_TYPE"0805"
SEC"1"
ROOM"HOT_SWAP"
CDS_LIB"mstr_discrete"
CDS_LOCATION"C9R5";
"A"
$PN"1"10;
"B"
$PN"2"7;
%"CAP"
"1","(-3375,3650)","0","mstr_discrete","I32";
;
CDS_SEC"1"
POP"NOPOP"
PART_NUMBER"C95333-007"
PACK_TYPE"0805"
TOLERANCE"10%"
VALUE"10UF"
LOCATION"C1E12"
MATERIAL"X6S"
VOLTAGE"16V"
SEC_TYPE"0805"
SEC"1"
CDS_LOCATION"C1E12"
ROOM"HOT_SWAP"
CDS_LIB"mstr_discrete";
"A"
$PN"1"10;
"B"
$PN"2"7;
%"GND"
"1","(-2500,1900)","0","mstr_symbols","I33";
;
VOLTAGE"0.0V"
CDS_LIB"mstr_symbols"
SIZE"1B"
BODY_TYPE"PLUMBING"
HDL_POWER"GND";
"A\NAC"8;
%"P12V_PSU"
"1","(-2350,2750)","0","mstr_symbols","I34";
;
ROOM"P2V5_LAN_AUX_VR"
BOM_COST"NT_BASE_VRD"
CDS_LIB"mstr_symbols"
VOLTAGE"12.0"
BODY_TYPE"PLUMBING"
HDL_POWER"P12V_PSU";
"G\NAC"9;
%"CAP"
"1","(-3025,3650)","0","mstr_discrete","I35";
;
CDS_SEC"1"
POP"NOPOP"
LOCATION"C1E15"
VALUE"10UF"
TOLERANCE"10%"
VOLTAGE"16V"
MATERIAL"X6S"
PACK_TYPE"0805"
PART_NUMBER"C95333-007"
SEC"1"
SEC_TYPE"0805"
ROOM"HOT_SWAP"
CDS_LOCATION"C1E15"
CDS_LIB"mstr_discrete";
"A"
$PN"1"10;
"B"
$PN"2"7;
%"CAP_A"
"1","(-2675,3650)","0","dev_discrete","I36";
;
LOCATION"C9R12"
VALUE"0.1UF"
VOLTAGE"16V"
TOLERANCE"10%"
MATERIAL"X7R"
PART_NUMBER"A36096-030"
PACK_TYPE"0402V"
POP"NOPOP"
SEC_TYPE"0402V"
SEC"1"
BOM_COST"HOT_SWAP"
CDS_SEC"1"
CDS_LIB"dev_discrete"
ROOM"HOT_SWAP"
CDS_LOCATION"C9R12";
"B"
$PN"2"7;
"A"
$PN"1"10;
%"CAP_A"
"1","(-2300,3650)","0","dev_discrete","I37";
;
PART_NUMBER"A36096-030"
PACK_TYPE"0402V"
VALUE"0.1UF"
VOLTAGE"16V"
TOLERANCE"10%"
LOCATION"C9R6"
MATERIAL"X7R"
POP"NOPOP"
SEC"1"
SEC_TYPE"0402V"
CDS_SEC"1"
BOM_COST"HOT_SWAP"
ROOM"HOT_SWAP"
CDS_LOCATION"C9R6"
CDS_LIB"dev_discrete";
"B"
$PN"2"7;
"A"
$PN"1"10;
%"CAP_A"
"1","(-1950,3650)","0","dev_discrete","I38";
;
VOLTAGE"16V"
POP"NOPOP"
PART_NUMBER"A36096-030"
LOCATION"C1E17"
VALUE"0.1UF"
TOLERANCE"10%"
MATERIAL"X7R"
PACK_TYPE"0402V"
SEC"1"
SEC_TYPE"0402V"
CDS_SEC"1"
BOM_COST"HOT_SWAP"
ROOM"HOT_SWAP"
CDS_LOCATION"C1E17"
CDS_LIB"dev_discrete";
"B"
$PN"2"7;
"A"
$PN"1"10;
%"CAP_A"
"1","(-1625,3650)","0","dev_discrete","I39";
;
POP"NOPOP"
PART_NUMBER"A36096-030"
MATERIAL"X7R"
VOLTAGE"16V"
TOLERANCE"10%"
VALUE"0.1UF"
LOCATION"C1E16"
PACK_TYPE"0402V"
CDS_LIB"dev_discrete"
CDS_LOCATION"C1E16"
ROOM"HOT_SWAP"
CDS_SEC"1"
SEC"1"
SEC_TYPE"0402V"
BOM_COST"HOT_SWAP";
"B"
$PN"2"7;
"A"
$PN"1"10;
%"P12V_PSU"
"1","(-1625,4025)","0","mstr_symbols","I40";
;
VOLTAGE"12.0"
CDS_LIB"mstr_symbols"
ROOM"P2V5_LAN_AUX_VR"
BOM_COST"NT_BASE_VRD"
BODY_TYPE"PLUMBING"
HDL_POWER"P12V_PSU";
"G\NAC"10;
%"GND"
"1","(-6900,4525)","0","mstr_symbols","I48";
;
SIZE"1B"
CDS_LIB"mstr_symbols"
VOLTAGE"0.0V"
BODY_TYPE"PLUMBING"
HDL_POWER"GND";
"A\NAC"11;
%"MTG_KEYHOLE"
"1","(-6475,4725)","0","mstr_misc","I49";
;
LOCATION"TH4G1"
MATERIAL"EMPTY"
PART_NUMBER"NA"
$SEC"1"
ROOM"MOUNTING_HOLES"
CDS_LOCATION"TH4G1"
BOM_COST"TEST_MFG"
CDS_SEC"1"
PACK_TYPE"TH"
CDS_LIB"mstr_misc";
"1"
$PN"1"11;
%"MTG_KEYHOLE"
"1","(-6425,4125)","0","mstr_misc","I52";
;
MATERIAL"EMPTY"
PART_NUMBER"NA"
LOCATION"TH9G1"
CDS_LOCATION"TH9G1"
CDS_LIB"mstr_misc"
ROOM"MOUNTING_HOLES"
$SEC"1"
CDS_SEC"1"
BOM_COST"TEST_MFG"
PACK_TYPE"TH";
"1"
$PN"1"12;
%"GND"
"1","(-6850,3925)","0","mstr_symbols","I53";
;
VOLTAGE"0.0V"
CDS_LIB"mstr_symbols"
SIZE"1B"
BODY_TYPE"PLUMBING"
HDL_POWER"GND";
"A\NAC"12;
%"MTG_KEYHOLE"
"1","(-4600,4725)","0","mstr_misc","I54";
;
PART_NUMBER"NA"
LOCATION"TH9A1"
MATERIAL"EMPTY"
ROOM"MOUNTING_HOLES"
CDS_LOCATION"TH9A1"
$SEC"1"
CDS_SEC"1"
BOM_COST"TEST_MFG"
PACK_TYPE"TH"
CDS_LIB"mstr_misc";
"1"
$PN"1"13;
%"GND"
"1","(-5025,4525)","0","mstr_symbols","I55";
;
CDS_LIB"mstr_symbols"
SIZE"1B"
VOLTAGE"0.0V"
BODY_TYPE"PLUMBING"
HDL_POWER"GND";
"A\NAC"13;
%"MTG_KEYHOLE"
"1","(-5525,4725)","0","mstr_misc","I56";
;
PART_NUMBER"NA"
MATERIAL"EMPTY"
LOCATION"TH1A1"
PACK_TYPE"TH"
BOM_COST"TEST_MFG"
CDS_SEC"1"
$SEC"1"
CDS_LOCATION"TH1A1"
ROOM"MOUNTING_HOLES"
CDS_LIB"mstr_misc";
"1"
$PN"1"14;
%"GND"
"1","(-5950,4525)","0","mstr_symbols","I57";
;
CDS_LIB"mstr_symbols"
VOLTAGE"0.0V"
SIZE"1B"
BODY_TYPE"PLUMBING"
HDL_POWER"GND";
"A\NAC"14;
%"MTG_KEYHOLE"
"1","(-7350,4125)","0","mstr_misc","I62";
;
MATERIAL"EMPTY"
PART_NUMBER"NA"
LOCATION"TH4A1"
ROOM"MOUNTING_HOLES"
CDS_LOCATION"TH4A1"
$SEC"1"
CDS_SEC"1"
BOM_COST"TEST_MFG"
PACK_TYPE"TH"
CDS_LIB"mstr_misc";
"1"
$PN"1"15;
%"GND"
"1","(-7775,3925)","0","mstr_symbols","I63";
;
SIZE"1B"
CDS_LIB"mstr_symbols"
VOLTAGE"0.0V"
BODY_TYPE"PLUMBING"
HDL_POWER"GND";
"A\NAC"15;
%"GND"
"1","(-5950,3950)","0","mstr_symbols","I64";
;
VOLTAGE"0.0V"
SIZE"1B"
CDS_LIB"mstr_symbols"
BODY_TYPE"PLUMBING"
HDL_POWER"GND";
"A\NAC"16;
%"MTG_KEYHOLE"
"1","(-5525,4150)","0","mstr_misc","I65";
;
MATERIAL"EMPTY"
PART_NUMBER"NA"
LOCATION"TH7A1"
PACK_TYPE"TH"
BOM_COST"TEST_MFG"
CDS_SEC"1"
$SEC"1"
CDS_LOCATION"TH7A1"
ROOM"MOUNTING_HOLES"
CDS_LIB"mstr_misc";
"1"
$PN"1"16;
%"GND"
"1","(-5025,3950)","0","mstr_symbols","I66";
;
CDS_LIB"mstr_symbols"
SIZE"1B"
VOLTAGE"0.0V"
BODY_TYPE"PLUMBING"
HDL_POWER"GND";
"A\NAC"17;
%"MTG_KEYHOLE"
"1","(-4600,4150)","0","mstr_misc","I67";
;
PART_NUMBER"NA"
MATERIAL"EMPTY"
LOCATION"TH7G1"
CDS_LOCATION"TH7G1"
ROOM"MOUNTING_HOLES"
$SEC"1"
CDS_SEC"1"
BOM_COST"TEST_MFG"
PACK_TYPE"TH"
CDS_LIB"mstr_misc";
"1"
$PN"1"17;
%"P12V_PSU"
"1","(-550,2750)","0","mstr_symbols","I77";
;
VOLTAGE"12.0"
BOM_COST"NT_BASE_VRD"
CDS_LIB"mstr_symbols"
ROOM"P2V5_LAN_AUX_VR"
BODY_TYPE"PLUMBING"
HDL_POWER"P12V_PSU";
"G\NAC"18;
%"GND"
"1","(-650,1900)","0","mstr_symbols","I79";
;
VOLTAGE"0.0V"
SIZE"1B"
CDS_LIB"mstr_symbols"
BODY_TYPE"PLUMBING"
HDL_POWER"GND";
"A\NAC"19;
%"P12V_PSU"
"1","(-1900,2750)","0","mstr_symbols","I80";
;
VOLTAGE"12.0"
CDS_LIB"mstr_symbols"
BOM_COST"NT_BASE_VRD"
ROOM"P2V5_LAN_AUX_VR"
BODY_TYPE"PLUMBING"
HDL_POWER"P12V_PSU";
"G\NAC"20;
%"GND"
"1","(-1850,1900)","0","mstr_symbols","I81";
;
VOLTAGE"0.0V"
CDS_LIB"mstr_symbols"
SIZE"1B"
BODY_TYPE"PLUMBING"
HDL_POWER"GND";
"A\NAC"21;
%"CAPP"
"1","(-7175,2950)","0","mstr_discrete","I82";
;
MATERIAL"ALUM"
VOLTAGE"16V"
TOLERANCE"20%"
VALUE"470UF"
PART_NUMBER"A93539-036"
LOCATION"C4F6"
PACK_TYPE"4040LF"
CDS_LIB"mstr_discrete"
CDS_LOCATION"C4F6"
CDS_SEC"1"
$SEC"1";
"B"
$PN"2"25;
"A"
$PN"1"22;
%"CAPP"
"1","(-6675,2950)","0","mstr_discrete","I83";
;
MATERIAL"ALUM"
VOLTAGE"16V"
PACK_TYPE"4040LF"
TOLERANCE"20%"
VALUE"470UF"
PART_NUMBER"A93539-036"
LOCATION"C4B13"
CDS_LIB"mstr_discrete"
CDS_LOCATION"C4B13"
CDS_SEC"1"
$SEC"1";
"B"
$PN"2"25;
"A"
$PN"1"22;
%"CAPP"
"1","(-6150,2925)","0","mstr_discrete","I84";
;
VOLTAGE"16V"
PACK_TYPE"4040LF"
TOLERANCE"20%"
VALUE"470UF"
LOCATION"C1B14"
PART_NUMBER"A93539-036"
MATERIAL"ALUM"
CDS_LIB"mstr_discrete"
CDS_LOCATION"C1B14"
CDS_SEC"1"
$SEC"1";
"B"
$PN"2"25;
"A"
$PN"1"22;
%"CAPP"
"1","(-5650,2900)","0","mstr_discrete","I85";
;
VOLTAGE"16V"
LOCATION"C1F7"
PART_NUMBER"A93539-036"
VALUE"470UF"
TOLERANCE"20%"
PACK_TYPE"4040LF"
MATERIAL"ALUM"
CDS_LIB"mstr_discrete"
CDS_LOCATION"C1F7"
$SEC"1"
CDS_SEC"1";
"B"
$PN"2"25;
"A"
$PN"1"22;
%"P12V_STBY"
"1","(-6250,3375)","0","mstr_symbols","I92";
;
SIZE"1B"
CDS_LIB"mstr_symbols"
VOLTAGE"12.0V"
BODY_TYPE"PLUMBING"
HDL_POWER"P12V_STBY";
"G\NAC"22;
%"P12V_STBY"
"1","(-6400,1150)","0","mstr_symbols","I93";
;
VOLTAGE"12.0V"
CDS_LIB"mstr_symbols"
SIZE"1B"
BODY_TYPE"PLUMBING"
HDL_POWER"P12V_STBY";
"G\NAC"23;
%"GND"
"1","(-6400,325)","0","mstr_symbols","I94";
;
VOLTAGE"0.0V"
CDS_LIB"mstr_symbols"
SIZE"1B"
BODY_TYPE"PLUMBING"
HDL_POWER"GND";
"A\NAC"24;
%"GND"
"1","(-6375,2550)","0","mstr_symbols","I95";
;
VOLTAGE"0.0V"
SIZE"1B"
CDS_LIB"mstr_symbols"
BODY_TYPE"PLUMBING"
HDL_POWER"GND";
"A\NAC"25;
%"CAPP"
"1","(-7275,775)","0","mstr_discrete","I96";
;
CDS_SEC"1"
PACK_TYPE"3018"
VOLTAGE"16V"
MATERIAL"TANT"
PART_NUMBER"724613-112"
TOLERANCE"20%"
VALUE"68UF"
LOCATION"C4F5"
SEC_TYPE"3018"
SEC"1"
CDS_LIB"mstr_discrete"
CDS_LOCATION"C4F5";
"B"
$PN"2"24;
"A"
$PN"1"23;
%"CAPP"
"1","(-6900,775)","0","mstr_discrete","I97";
;
CDS_SEC"1"
PACK_TYPE"3018"
VOLTAGE"16V"
MATERIAL"TANT"
VALUE"68UF"
LOCATION"C4B14"
TOLERANCE"20%"
PART_NUMBER"724613-112"
SEC_TYPE"3018"
SEC"1"
CDS_LIB"mstr_discrete"
CDS_LOCATION"C4B14";
"B"
$PN"2"24;
"A"
$PN"1"23;
%"CAPP"
"1","(-5300,750)","0","mstr_discrete","I98";
;
CDS_SEC"1"
VOLTAGE"16V"
PACK_TYPE"3018"
TOLERANCE"20%"
MATERIAL"TANT"
PART_NUMBER"724613-112"
VALUE"68UF"
LOCATION"C3T6"
SEC_TYPE"3018"
SEC"1"
CDS_LIB"mstr_discrete"
CDS_LOCATION"C3T6";
"B"
$PN"2"24;
"A"
$PN"1"23;
%"CAPP"
"1","(-5750,775)","0","mstr_discrete","I99";
;
CDS_SEC"1"
MATERIAL"TANT"
PACK_TYPE"3018"
PART_NUMBER"724613-112"
VOLTAGE"16V"
TOLERANCE"20%"
VALUE"68UF"
LOCATION"C9M3"
SEC_TYPE"3018"
SEC"1"
CDS_LIB"mstr_discrete"
CDS_LOCATION"C9M3";
"B"
$PN"2"24;
"A"
$PN"1"23;
END.
